(kicad_pcb
	(version 20260206)
	(generator "pcbnew")
	(generator_version "10.0")
	(general
		(thickness 1.6)
		(legacy_teardrops no)
	)
	(paper "A4")
	(title_block
		(title "Bryce Canyon_IOM_M2_16342-2_OCP.brd")
		(comment 1 "Bryce Canyon / footprints 477-482 of 1146")
	)
	(layers
		(0 "F.Cu" signal "TOP")
		(4 "In1.Cu" signal "L2GND")
		(6 "In2.Cu" signal "L3")
		(8 "In3.Cu" signal "L4VCC")
		(10 "In4.Cu" signal "L5VCC")
		(12 "In5.Cu" signal "L6")
		(14 "In6.Cu" signal "L7GND")
		(2 "B.Cu" signal "BOTTOM")
		(9 "F.Adhes" user "F.Adhesive")
		(11 "B.Adhes" user "B.Adhesive")
		(13 "F.Paste" user "Package Geometry/Pastemask Top")
		(15 "B.Paste" user "Package Geometry/Pastemask Bottom")
		(5 "F.SilkS" user "Ref Des/Silkscreen Top")
		(7 "B.SilkS" user "Ref Des/Silkscreen Bottom")
		(1 "F.Mask" user "Board Geometry/Soldermask Top")
		(3 "B.Mask" user "Board Geometry/Soldermask Bottom")
		(17 "Dwgs.User" user "User.Drawings")
		(19 "Cmts.User" user "User.Comments")
		(21 "Eco1.User" user "User.Eco1")
		(23 "Eco2.User" user "User.Eco2")
		(25 "Edge.Cuts" user "Board Geometry/Outline")
		(27 "Margin" user)
		(31 "F.CrtYd" user "Package Geometry/Place Bound Top")
		(29 "B.CrtYd" user "Package Geometry/Place Bound Bottom")
		(35 "F.Fab" user "Ref Des/Assembly Top")
		(33 "B.Fab" user "Ref Des/Assembly Bottom")
	)
	(footprint ""
		(layer "F.Cu")
		(at 60.301886 -133.2738 -90)
		(property "Reference" "R290"
			(at 0 0 270)
			(layer "F.SilkS")
			(hide yes)
			(effects
				(font
					(size 1.27 1.27)
				)
			)
		)
		(property "Value" "0R2J-2-GP"
			(at 0.064008 -3.993896 270)
			(unlocked yes)
			(layer "F.Fab")
			(hide yes)
			(effects
				(font
					(size 1.016 1.016)
					(thickness 0.1524)
				)
			)
		)
		(property "Device Type" "R402H16"
			(at 0.064008 -5.517896 270)
			(unlocked yes)
			(layer "F.Fab")
			(hide yes)
			(effects
				(font
					(size 1.016 1.016)
					(thickness 0.1524)
				)
			)
		)
		(duplicate_pad_numbers_are_jumpers no)
		(fp_line
			(start -0.508 -0.9398)
			(end -0.508 0.9398)
			(stroke
				(width 0.1524)
				(type default)
			)
			(layer "F.SilkS")
		)
		(fp_line
			(start 0.508 -0.9398)
			(end -0.508 -0.9398)
			(stroke
				(width 0.1524)
				(type default)
			)
			(layer "F.SilkS")
		)
		(fp_rect
			(start -0.508 0.9398)
			(end 0.508 -0.9398)
			(stroke
				(width 0)
				(type default)
			)
			(fill no)
			(layer "F.CrtYd")
		)
		(fp_rect
			(start -0.508 0.9398)
			(end 0.508 -0.9398)
			(stroke
				(width 0)
				(type default)
			)
			(fill no)
			(layer "F.Fab")
		)
		(pad "1" smd custom
			(at 0 -0.4445 270)
			(size 0.1397 0.1397)
			(layers "F.Cu" "F.Mask" "F.Paste")
			(net "SCC_STBY_PWR_EN")
			(options
				(clearance outline)
				(anchor circle)
			)
			(primitives
				(gr_poly
					(pts
						(arc
							(start -0.1778 -0.2794)
							(mid -0.249642 -0.249642)
							(end -0.2794 -0.1778)
						)
						(arc
							(start -0.2794 0.1778)
							(mid -0.249642 0.249642)
							(end -0.1778 0.2794)
						)
						(arc
							(start 0.1778 0.2794)
							(mid 0.249642 0.249642)
							(end 0.2794 0.1778)
						)
						(arc
							(start 0.2794 -0.1778)
							(mid 0.249642 -0.249642)
							(end 0.1778 -0.2794)
						)
					)
					(width 0)
					(fill yes)
				)
			)
		)
		(pad "2" smd custom
			(at 0 0.4445 270)
			(size 0.1397 0.1397)
			(layers "F.Cu" "F.Mask" "F.Paste")
			(net "SCC_PWR_EN_R")
			(options
				(clearance outline)
				(anchor circle)
			)
			(primitives
				(gr_poly
					(pts
						(arc
							(start -0.1778 -0.2794)
							(mid -0.249642 -0.249642)
							(end -0.2794 -0.1778)
						)
						(arc
							(start -0.2794 0.1778)
							(mid -0.249642 0.249642)
							(end -0.1778 0.2794)
						)
						(arc
							(start 0.1778 0.2794)
							(mid 0.249642 0.249642)
							(end 0.2794 0.1778)
						)
						(arc
							(start 0.2794 -0.1778)
							(mid 0.249642 -0.249642)
							(end 0.1778 -0.2794)
						)
					)
					(width 0)
					(fill yes)
				)
			)
		)
	)
	(footprint ""
		(layer "F.Cu")
		(at 226.596702 -51.1429 90)
		(property "Reference" "C152"
			(at 0 0 90)
			(layer "F.SilkS")
			(hide yes)
			(effects
				(font
					(size 1.27 1.27)
				)
			)
		)
		(property "Value" "SC10U16V5KX-7-GP-U"
			(at -0.0762 -6.1214 90)
			(unlocked yes)
			(layer "F.Fab")
			(hide yes)
			(effects
				(font
					(size 1.016 1.016)
					(thickness 0.1524)
				)
			)
		)
		(property "Device Type" "C805H58"
			(at -0.0762 -8.1534 90)
			(unlocked yes)
			(layer "F.Fab")
			(hide yes)
			(effects
				(font
					(size 1.016 1.016)
					(thickness 0.1524)
				)
			)
		)
		(duplicate_pad_numbers_are_jumpers no)
		(fp_line
			(start 0.635 0)
			(end -0.635 0)
			(stroke
				(width 0.508)
				(type default)
			)
			(layer "F.SilkS")
		)
		(fp_rect
			(start -0.9652 1.778)
			(end 0.9652 -1.778)
			(stroke
				(width 0)
				(type default)
			)
			(fill no)
			(layer "F.CrtYd")
		)
		(fp_poly
			(pts
				(xy -0.9652 -1.778) (xy 0.9652 -1.778) (xy 0.9652 1.778) (xy -0.9652 1.778)
			)
			(stroke
				(width 0)
				(type default)
			)
			(fill no)
			(layer "F.Fab")
		)
		(pad "1" smd rect
			(at 0 -0.9652 90)
			(size 1.397 1.143)
			(layers "F.Cu" "F.Mask" "F.Paste")
			(net "P12V_STBY_VIN_PU1")
		)
		(pad "2" smd rect
			(at 0 0.9652 90)
			(size 1.397 1.143)
			(layers "F.Cu" "F.Mask" "F.Paste")
			(net "GND")
		)
	)
	(footprint ""
		(layer "F.Cu")
		(at 77.8002 -162.2044 -90)
		(property "Reference" "PU11"
			(at 0 0 270)
			(layer "F.SilkS")
			(hide yes)
			(effects
				(font
					(size 1.27 1.27)
				)
			)
		)
		(property "Value" "TPS74801RGW-GP"
			(at -4.7244 -6.223 270)
			(unlocked yes)
			(layer "F.Fab")
			(hide yes)
			(effects
				(font
					(size 1.016 1.016)
					(thickness 0.1524)
				)
			)
		)
		(property "Device Type" "QFN20-1G3D15H40"
			(at -4.7244 -7.747 270)
			(unlocked yes)
			(layer "F.Fab")
			(hide yes)
			(effects
				(font
					(size 1.016 1.016)
					(thickness 0.1524)
				)
			)
		)
		(duplicate_pad_numbers_are_jumpers no)
		(fp_line
			(start -3.5179 3.5179)
			(end -2.2479 3.5179)
			(stroke
				(width 0.1524)
				(type default)
			)
			(layer "F.SilkS")
		)
		(fp_line
			(start 2.2479 3.5179)
			(end 3.5179 3.5179)
			(stroke
				(width 0.1524)
				(type default)
			)
			(layer "F.SilkS")
		)
		(fp_line
			(start 3.5179 3.5179)
			(end 3.5179 2.2479)
			(stroke
				(width 0.1524)
				(type default)
			)
			(layer "F.SilkS")
		)
		(fp_line
			(start 1.299972 3.160522)
			(end 1.299972 3.668522)
			(stroke
				(width 0.1524)
				(type default)
			)
			(layer "F.SilkS")
		)
		(fp_line
			(start -3.5179 2.2479)
			(end -3.5179 3.5179)
			(stroke
				(width 0.1524)
				(type default)
			)
			(layer "F.SilkS")
		)
		(fp_line
			(start -3.160522 1.299972)
			(end -3.922522 1.299972)
			(stroke
				(width 0.1524)
				(type default)
			)
			(layer "F.SilkS")
		)
		(fp_line
			(start 3.160522 -1.299972)
			(end 3.922522 -1.299972)
			(stroke
				(width 0.1524)
				(type default)
			)
			(layer "F.SilkS")
		)
		(fp_line
			(start -1.299972 -3.160522)
			(end -1.299972 -3.668522)
			(stroke
				(width 0.1524)
				(type default)
			)
			(layer "F.SilkS")
		)
		(fp_line
			(start -3.5179 -3.5179)
			(end -3.5179 -2.2479)
			(stroke
				(width 0.1524)
				(type default)
			)
			(layer "F.SilkS")
		)
		(fp_line
			(start -2.2479 -3.5179)
			(end -3.5179 -3.5179)
			(stroke
				(width 0.1524)
				(type default)
			)
			(layer "F.SilkS")
		)
		(fp_poly
			(pts
				(xy 3.5179 -3.5179) (xy 2.2479 -3.5179) (xy 3.5179 -2.2479)
			)
			(stroke
				(width 0)
				(type default)
			)
			(fill yes)
			(layer "F.SilkS")
		)
		(fp_rect
			(start -2.5019 2.5019)
			(end 2.5019 -2.5019)
			(stroke
				(width 0)
				(type default)
			)
			(fill no)
			(layer "F.CrtYd")
		)
		(fp_poly
			(pts
				(xy -3.5179 3.5179) (xy -3.5179 -3.5179) (xy 3.5179 -3.5179) (xy 3.5179 -2.5019) (xy -2.5019 -2.5019)
				(xy -2.5019 2.5019) (xy 2.5019 2.5019) (xy 2.5019 -2.49682) (xy 3.5179 -2.49682) (xy 3.5179 3.5179)
			)
			(stroke
				(width 0)
				(type default)
			)
			(fill no)
			(layer "F.CrtYd")
		)
		(fp_rect
			(start -3.5179 3.5179)
			(end 3.5179 -3.5179)
			(stroke
				(width 0)
				(type default)
			)
			(fill no)
			(layer "F.Fab")
		)
		(pad "1" smd rect
			(at 1.299972 -2.474722 270)
			(size 0.3556 1.0668)
			(layers "F.Cu" "F.Mask" "F.Paste")
			(net "TPS74801_P1V15_STBY_OUT")
		)
		(pad "2" smd rect
			(at 0.649986 -2.474722 270)
			(size 0.3556 1.0668)
			(layers "F.Cu" "F.Mask" "F.Paste")
			(net "GND")
		)
		(pad "3" smd rect
			(at 0 -2.474722 270)
			(size 0.3556 1.0668)
			(layers "F.Cu" "F.Mask" "F.Paste")
			(net "GND")
		)
		(pad "4" smd rect
			(at -0.649986 -2.474722 270)
			(size 0.3556 1.0668)
			(layers "F.Cu" "F.Mask" "F.Paste")
			(net "GND")
		)
		(pad "5" smd rect
			(at -1.299972 -2.474722 270)
			(size 0.3556 1.0668)
			(layers "F.Cu" "F.Mask" "F.Paste")
			(net "P1V8_STBY")
		)
		(pad "6" smd rect
			(at -2.474722 -1.299972 270)
			(size 1.0668 0.3556)
			(layers "F.Cu" "F.Mask" "F.Paste")
			(net "P1V8_STBY")
		)
		(pad "7" smd rect
			(at -2.474722 -0.649986 270)
			(size 1.0668 0.3556)
			(layers "F.Cu" "F.Mask" "F.Paste")
			(net "P1V8_STBY")
		)
		(pad "8" smd rect
			(at -2.474722 0 270)
			(size 1.0668 0.3556)
			(layers "F.Cu" "F.Mask" "F.Paste")
			(net "P1V8_STBY")
		)
		(pad "9" smd rect
			(at -2.474722 0.649986 270)
			(size 1.0668 0.3556)
			(layers "F.Cu" "F.Mask" "F.Paste")
			(net "P1V15_STBY_PG")
		)
		(pad "10" smd rect
			(at -2.474722 1.299972 270)
			(size 1.0668 0.3556)
			(layers "F.Cu" "F.Mask" "F.Paste")
			(net "TPS74801_P1V15_STBY_BIAS")
		)
		(pad "11" smd rect
			(at -1.299972 2.474722 270)
			(size 0.3556 1.0668)
			(layers "F.Cu" "F.Mask" "F.Paste")
			(net "TPS74801_P1V15_STBY_EN")
		)
		(pad "12" smd rect
			(at -0.649986 2.474722 270)
			(size 0.3556 1.0668)
			(layers "F.Cu" "F.Mask" "F.Paste")
			(net "GND")
		)
		(pad "13" smd rect
			(at 0 2.474722 270)
			(size 0.3556 1.0668)
			(layers "F.Cu" "F.Mask" "F.Paste")
			(net "GND")
		)
		(pad "14" smd rect
			(at 0.649986 2.474722 270)
			(size 0.3556 1.0668)
			(layers "F.Cu" "F.Mask" "F.Paste")
			(net "GND")
		)
		(pad "15" smd rect
			(at 1.299972 2.474722 270)
			(size 0.3556 1.0668)
			(layers "F.Cu" "F.Mask" "F.Paste")
			(net "TPS74801_P1V15_STBY_SS")
		)
		(pad "16" smd rect
			(at 2.474722 1.299972 270)
			(size 1.0668 0.3556)
			(layers "F.Cu" "F.Mask" "F.Paste")
			(net "TPS74801_P1V15_STBY_FB")
		)
		(pad "17" smd rect
			(at 2.474722 0.649986 270)
			(size 1.0668 0.3556)
			(layers "F.Cu" "F.Mask" "F.Paste")
			(net "GND")
		)
		(pad "18" smd rect
			(at 2.474722 0 270)
			(size 1.0668 0.3556)
			(layers "F.Cu" "F.Mask" "F.Paste")
			(net "TPS74801_P1V15_STBY_OUT")
		)
		(pad "19" smd rect
			(at 2.474722 -0.649986 270)
			(size 1.0668 0.3556)
			(layers "F.Cu" "F.Mask" "F.Paste")
			(net "TPS74801_P1V15_STBY_OUT")
		)
		(pad "20" smd rect
			(at 2.474722 -1.299972 270)
			(size 1.0668 0.3556)
			(layers "F.Cu" "F.Mask" "F.Paste")
			(net "TPS74801_P1V15_STBY_OUT")
		)
		(pad "21" smd rect
			(at 0 0 270)
			(size 3.2512 3.2512)
			(layers "F.Cu" "F.Mask" "F.Paste")
			(net "GND")
		)
	)
	(footprint ""
		(layer "F.Cu")
		(at 77.407262 -157.6197 90)
		(property "Reference" "R538"
			(at 0 0 90)
			(layer "F.SilkS")
			(hide yes)
			(effects
				(font
					(size 1.27 1.27)
				)
			)
		)
		(property "Value" "4K64R2F-GP"
			(at 0.064008 -3.993896 90)
			(unlocked yes)
			(layer "F.Fab")
			(hide yes)
			(effects
				(font
					(size 1.016 1.016)
					(thickness 0.1524)
				)
			)
		)
		(property "Device Type" "R402H16"
			(at 0.064008 -5.517896 90)
			(unlocked yes)
			(layer "F.Fab")
			(hide yes)
			(effects
				(font
					(size 1.016 1.016)
					(thickness 0.1524)
				)
			)
		)
		(duplicate_pad_numbers_are_jumpers no)
		(fp_line
			(start 0.508 -0.9398)
			(end -0.508 -0.9398)
			(stroke
				(width 0.1524)
				(type default)
			)
			(layer "F.SilkS")
		)
		(fp_line
			(start -0.508 -0.9398)
			(end -0.508 0.9398)
			(stroke
				(width 0.1524)
				(type default)
			)
			(layer "F.SilkS")
		)
		(fp_rect
			(start -0.508 0.9398)
			(end 0.508 -0.9398)
			(stroke
				(width 0)
				(type default)
			)
			(fill no)
			(layer "F.CrtYd")
		)
		(fp_rect
			(start -0.508 0.9398)
			(end 0.508 -0.9398)
			(stroke
				(width 0)
				(type default)
			)
			(fill no)
			(layer "F.Fab")
		)
		(pad "1" smd custom
			(at 0 -0.4445 90)
			(size 0.1397 0.1397)
			(layers "F.Cu" "F.Mask" "F.Paste")
			(net "TPS74801_P1V15_STBY_FB")
			(options
				(clearance outline)
				(anchor circle)
			)
			(primitives
				(gr_poly
					(pts
						(arc
							(start -0.1778 -0.2794)
							(mid -0.249642 -0.249642)
							(end -0.2794 -0.1778)
						)
						(arc
							(start -0.2794 0.1778)
							(mid -0.249642 0.249642)
							(end -0.1778 0.2794)
						)
						(arc
							(start 0.1778 0.2794)
							(mid 0.249642 0.249642)
							(end 0.2794 0.1778)
						)
						(arc
							(start 0.2794 -0.1778)
							(mid 0.249642 -0.249642)
							(end 0.1778 -0.2794)
						)
					)
					(width 0)
					(fill yes)
				)
			)
		)
		(pad "2" smd custom
			(at 0 0.4445 90)
			(size 0.1397 0.1397)
			(layers "F.Cu" "F.Mask" "F.Paste")
			(net "GND")
			(options
				(clearance outline)
				(anchor circle)
			)
			(primitives
				(gr_poly
					(pts
						(arc
							(start -0.1778 -0.2794)
							(mid -0.249642 -0.249642)
							(end -0.2794 -0.1778)
						)
						(arc
							(start -0.2794 0.1778)
							(mid -0.249642 0.249642)
							(end -0.1778 0.2794)
						)
						(arc
							(start 0.1778 0.2794)
							(mid 0.249642 0.249642)
							(end 0.2794 0.1778)
						)
						(arc
							(start 0.2794 -0.1778)
							(mid 0.249642 -0.249642)
							(end 0.1778 -0.2794)
						)
					)
					(width 0)
					(fill yes)
				)
			)
		)
	)
	(footprint ""
		(layer "F.Cu")
		(at 55.6768 -162.687 180)
		(property "Reference" "R405"
			(at 0 0 180)
			(layer "F.SilkS")
			(hide yes)
			(effects
				(font
					(size 1.27 1.27)
				)
			)
		)
		(property "Value" "1KR2F-3-GP"
			(at 0.064008 -3.993896 180)
			(unlocked yes)
			(layer "F.Fab")
			(hide yes)
			(effects
				(font
					(size 1.016 1.016)
					(thickness 0.1524)
				)
			)
		)
		(property "Device Type" "R402H16"
			(at 0.064008 -5.517896 180)
			(unlocked yes)
			(layer "F.Fab")
			(hide yes)
			(effects
				(font
					(size 1.016 1.016)
					(thickness 0.1524)
				)
			)
		)
		(duplicate_pad_numbers_are_jumpers no)
		(fp_line
			(start 0.508 -0.9398)
			(end -0.508 -0.9398)
			(stroke
				(width 0.1524)
				(type default)
			)
			(layer "F.SilkS")
		)
		(fp_line
			(start -0.508 -0.9398)
			(end -0.508 0.9398)
			(stroke
				(width 0.1524)
				(type default)
			)
			(layer "F.SilkS")
		)
		(fp_rect
			(start -0.508 0.9398)
			(end 0.508 -0.9398)
			(stroke
				(width 0)
				(type default)
			)
			(fill no)
			(layer "F.CrtYd")
		)
		(fp_rect
			(start -0.508 0.9398)
			(end 0.508 -0.9398)
			(stroke
				(width 0)
				(type default)
			)
			(fill no)
			(layer "F.Fab")
		)
		(pad "1" smd custom
			(at 0 -0.4445 180)
			(size 0.1397 0.1397)
			(layers "F.Cu" "F.Mask" "F.Paste")
			(net "ADC_P1V8_STBY")
			(options
				(clearance outline)
				(anchor circle)
			)
			(primitives
				(gr_poly
					(pts
						(arc
							(start -0.1778 -0.2794)
							(mid -0.249642 -0.249642)
							(end -0.2794 -0.1778)
						)
						(arc
							(start -0.2794 0.1778)
							(mid -0.249642 0.249642)
							(end -0.1778 0.2794)
						)
						(arc
							(start 0.1778 0.2794)
							(mid 0.249642 0.249642)
							(end 0.2794 0.1778)
						)
						(arc
							(start 0.2794 -0.1778)
							(mid 0.249642 -0.249642)
							(end 0.1778 -0.2794)
						)
					)
					(width 0)
					(fill yes)
				)
			)
		)
		(pad "2" smd custom
			(at 0 0.4445 180)
			(size 0.1397 0.1397)
			(layers "F.Cu" "F.Mask" "F.Paste")
			(net "GND")
			(options
				(clearance outline)
				(anchor circle)
			)
			(primitives
				(gr_poly
					(pts
						(arc
							(start -0.1778 -0.2794)
							(mid -0.249642 -0.249642)
							(end -0.2794 -0.1778)
						)
						(arc
							(start -0.2794 0.1778)
							(mid -0.249642 0.249642)
							(end -0.1778 0.2794)
						)
						(arc
							(start 0.1778 0.2794)
							(mid 0.249642 0.249642)
							(end 0.2794 0.1778)
						)
						(arc
							(start 0.2794 -0.1778)
							(mid 0.249642 -0.249642)
							(end 0.1778 -0.2794)
						)
					)
					(width 0)
					(fill yes)
				)
			)
		)
	)
	(footprint ""
		(layer "F.Cu")
		(at 205.2574 -110.7694)
		(property "Reference" "R549"
			(at 0 0 0)
			(layer "F.SilkS")
			(hide yes)
			(effects
				(font
					(size 1.27 1.27)
				)
			)
		)
		(property "Value" "4K7R2F-GP"
			(at 0.064008 -3.993896 0)
			(unlocked yes)
			(layer "F.Fab")
			(hide yes)
			(effects
				(font
					(size 1.016 1.016)
					(thickness 0.1524)
				)
			)
		)
		(property "Device Type" "R402H16"
			(at 0.064008 -5.517896 0)
			(unlocked yes)
			(layer "F.Fab")
			(hide yes)
			(effects
				(font
					(size 1.016 1.016)
					(thickness 0.1524)
				)
			)
		)
		(duplicate_pad_numbers_are_jumpers no)
		(fp_line
			(start -0.508 -0.9398)
			(end -0.508 0.9398)
			(stroke
				(width 0.1524)
				(type default)
			)
			(layer "F.SilkS")
		)
		(fp_line
			(start 0.508 -0.9398)
			(end -0.508 -0.9398)
			(stroke
				(width 0.1524)
				(type default)
			)
			(layer "F.SilkS")
		)
		(fp_rect
			(start -0.508 0.9398)
			(end 0.508 -0.9398)
			(stroke
				(width 0)
				(type default)
			)
			(fill no)
			(layer "F.CrtYd")
		)
		(fp_rect
			(start -0.508 0.9398)
			(end 0.508 -0.9398)
			(stroke
				(width 0)
				(type default)
			)
			(fill no)
			(layer "F.Fab")
		)
		(pad "1" smd custom
			(at 0 -0.4445)
			(size 0.1397 0.1397)
			(layers "F.Cu" "F.Mask" "F.Paste")
			(net "P3V3_STBY")
			(options
				(clearance outline)
				(anchor circle)
			)
			(primitives
				(gr_poly
					(pts
						(arc
							(start -0.1778 -0.2794)
							(mid -0.249642 -0.249642)
							(end -0.2794 -0.1778)
						)
						(arc
							(start -0.2794 0.1778)
							(mid -0.249642 0.249642)
							(end -0.1778 0.2794)
						)
						(arc
							(start 0.1778 0.2794)
							(mid 0.249642 0.249642)
							(end 0.2794 0.1778)
						)
						(arc
							(start 0.2794 -0.1778)
							(mid 0.249642 -0.249642)
							(end 0.1778 -0.2794)
						)
					)
					(width 0)
					(fill yes)
				)
			)
		)
		(pad "2" smd custom
			(at 0 0.4445)
			(size 0.1397 0.1397)
			(layers "F.Cu" "F.Mask" "F.Paste")
			(net "TEMP_2_A1")
			(options
				(clearance outline)
				(anchor circle)
			)
			(primitives
				(gr_poly
					(pts
						(arc
							(start -0.1778 -0.2794)
							(mid -0.249642 -0.249642)
							(end -0.2794 -0.1778)
						)
						(arc
							(start -0.2794 0.1778)
							(mid -0.249642 0.249642)
							(end -0.1778 0.2794)
						)
						(arc
							(start 0.1778 0.2794)
							(mid 0.249642 0.249642)
							(end 0.2794 0.1778)
						)
						(arc
							(start 0.2794 -0.1778)
							(mid 0.249642 -0.249642)
							(end 0.1778 -0.2794)
						)
					)
					(width 0)
					(fill yes)
				)
			)
		)
	)
)
